# SCM (Grand Teton) — schematic netlist excerpt (pin names and nets, part order shuffled) for the footprints in the layout excerpt that follows; sources: Cadence DE-HDL packaged netlist, KiCad conversion of 12092022_DA0F0TMDCD0_F0T_Management_Board_D_brd_V3_OCP.brd

R812  Q_RES  33.2 1% CHIP  pkg 0402LF  page 49 : A = PWR_LED_BUF_N ; B = PWR_LED_BUF_N_R
C290  Q_CAP  0.1UF 25V 10% X7R  pkg 0402  page 15 : A = P12V_SENSOR ; B = GND

(kicad_pcb
	(version 20260206)
	(generator "pcbnew")
	(generator_version "10.0")
	(general
		(thickness 1.6)
		(legacy_teardrops no)
	)
	(paper "A4")
	(title_block
		(title "12092022_DA0F0TMDCD0_F0T_Management_Board_D_brd_V3_OCP.brd")
		(comment 1 "Grand Teton / footprints 1281-1282 of 1440")
	)
	(layers
		(0 "F.Cu" signal "TOP")
		(4 "In1.Cu" signal "GND")
		(6 "In2.Cu" signal "IN1")
		(8 "In3.Cu" signal "GND1")
		(10 "In4.Cu" signal "IN2")
		(12 "In5.Cu" signal "VCC")
		(14 "In6.Cu" signal "VCC1")
		(16 "In7.Cu" signal "IN3")
		(18 "In8.Cu" signal "GND2")
		(20 "In9.Cu" signal "IN4")
		(22 "In10.Cu" signal "GND3")
		(2 "B.Cu" signal "BOTTOM")
		(9 "F.Adhes" user "F.Adhesive")
		(11 "B.Adhes" user "B.Adhesive")
		(13 "F.Paste" user "Package Geometry/Pastemask Top")
		(15 "B.Paste" user "Package Geometry/Pastemask Bottom")
		(5 "F.SilkS" user "Ref Des/Silkscreen Top")
		(7 "B.SilkS" user "Ref Des/Silkscreen Bottom")
		(1 "F.Mask" user "Board Geometry/Soldermask Top")
		(3 "B.Mask" user "Board Geometry/Soldermask Bottom")
		(17 "Dwgs.User" user "User.Drawings")
		(19 "Cmts.User" user "User.Comments")
		(21 "Eco1.User" user "User.Eco1")
		(23 "Eco2.User" user "User.Eco2")
		(25 "Edge.Cuts" user "Board Geometry/Outline")
		(27 "Margin" user)
		(31 "F.CrtYd" user "Package Geometry/Place Bound Top")
		(29 "B.CrtYd" user "Package Geometry/Place Bound Bottom")
		(35 "F.Fab" user "Ref Des/Assembly Top")
		(33 "B.Fab" user "Ref Des/Assembly Bottom")
	)
	(footprint ""
		(layer "B.Cu")
		(at 31.9532 -60.5282)
		(property "Reference" "C290"
			(at 0 0 0)
			(layer "B.SilkS")
			(hide yes)
			(effects
				(font
					(size 1.27 1.27)
				)
				(justify mirror)
			)
		)
		(property "Value" ""
			(at 0 0 0)
			(layer "B.Fab")
			(effects
				(font
					(size 1.27 1.27)
				)
				(justify mirror)
			)
		)
		(duplicate_pad_numbers_are_jumpers no)
		(fp_line
			(start -0.7874 -0.4064)
			(end -0.7874 0.4064)
			(stroke
				(width 0.1524)
				(type default)
			)
			(layer "B.SilkS")
		)
		(fp_line
			(start -0.7874 0.4064)
			(end 0.7874 0.4064)
			(stroke
				(width 0.1524)
				(type default)
			)
			(layer "B.SilkS")
		)
		(fp_line
			(start 0.7874 -0.4064)
			(end -0.7874 -0.4064)
			(stroke
				(width 0.1524)
				(type default)
			)
			(layer "B.SilkS")
		)
		(fp_line
			(start 0.7874 0.4064)
			(end 0.7874 -0.4064)
			(stroke
				(width 0.1524)
				(type default)
			)
			(layer "B.SilkS")
		)
		(fp_line
			(start -0.67945 -0.3048)
			(end -0.67945 0.3048)
			(stroke
				(width 0.1)
				(type default)
			)
			(layer "B.Fab")
		)
		(fp_line
			(start -0.67945 0.3048)
			(end -0.120396 0.3048)
			(stroke
				(width 0.1)
				(type default)
			)
			(layer "B.Fab")
		)
		(fp_line
			(start -0.12065 -0.3048)
			(end -0.67945 -0.3048)
			(stroke
				(width 0.1)
				(type default)
			)
			(layer "B.Fab")
		)
		(fp_line
			(start -0.12065 -0.2794)
			(end -0.12065 -0.3048)
			(stroke
				(width 0.1)
				(type default)
			)
			(layer "B.Fab")
		)
		(fp_line
			(start -0.120396 0.2794)
			(end 0.12065 0.2794)
			(stroke
				(width 0.1)
				(type default)
			)
			(layer "B.Fab")
		)
		(fp_line
			(start -0.120396 0.3048)
			(end -0.120396 0.2794)
			(stroke
				(width 0.1)
				(type default)
			)
			(layer "B.Fab")
		)
		(fp_line
			(start 0.12065 -0.305054)
			(end 0.12065 -0.2794)
			(stroke
				(width 0.1)
				(type default)
			)
			(layer "B.Fab")
		)
		(fp_line
			(start 0.12065 -0.2794)
			(end -0.12065 -0.2794)
			(stroke
				(width 0.1)
				(type default)
			)
			(layer "B.Fab")
		)
		(fp_line
			(start 0.12065 0.2794)
			(end 0.12065 0.3048)
			(stroke
				(width 0.1)
				(type default)
			)
			(layer "B.Fab")
		)
		(fp_line
			(start 0.12065 0.3048)
			(end 0.67945 0.3048)
			(stroke
				(width 0.1)
				(type default)
			)
			(layer "B.Fab")
		)
		(fp_line
			(start 0.67945 -0.305054)
			(end 0.12065 -0.305054)
			(stroke
				(width 0.1)
				(type default)
			)
			(layer "B.Fab")
		)
		(fp_line
			(start 0.67945 0.3048)
			(end 0.67945 -0.305054)
			(stroke
				(width 0.1)
				(type default)
			)
			(layer "B.Fab")
		)
		(pad "1" smd circle
			(at 0.40005 0 180)
			(size 0 0)
			(layers "B.Cu" "B.Mask" "B.Paste")
			(net "P12V_SENSOR")
		)
		(pad "2" smd circle
			(at -0.40005 0 180)
			(size 0 0)
			(layers "B.Cu" "B.Mask" "B.Paste")
			(net "GND")
		)
	)
	(footprint ""
		(layer "B.Cu")
		(at 14.478 -21.844 180)
		(property "Reference" "R812"
			(at 0 0 0)
			(layer "B.SilkS")
			(hide yes)
			(effects
				(font
					(size 1.27 1.27)
				)
				(justify mirror)
			)
		)
		(property "Value" ""
			(at 0 0 0)
			(layer "B.Fab")
			(effects
				(font
					(size 1.27 1.27)
				)
				(justify mirror)
			)
		)
		(duplicate_pad_numbers_are_jumpers no)
		(fp_line
			(start 0.7874 0.4064)
			(end 0.7874 -0.4064)
			(stroke
				(width 0.1524)
				(type default)
			)
			(layer "B.SilkS")
		)
		(fp_line
			(start 0.7874 -0.4064)
			(end -0.7874 -0.4064)
			(stroke
				(width 0.1524)
				(type default)
			)
			(layer "B.SilkS")
		)
		(fp_line
			(start -0.7874 0.4064)
			(end 0.7874 0.4064)
			(stroke
				(width 0.1524)
				(type default)
			)
			(layer "B.SilkS")
		)
		(fp_line
			(start -0.7874 -0.4064)
			(end -0.7874 0.4064)
			(stroke
				(width 0.1524)
				(type default)
			)
			(layer "B.SilkS")
		)
		(fp_line
			(start 0.67945 0.3048)
			(end 0.67945 -0.305054)
			(stroke
				(width 0.1)
				(type default)
			)
			(layer "B.Fab")
		)
		(fp_line
			(start 0.67945 -0.305054)
			(end 0.12065 -0.305054)
			(stroke
				(width 0.1)
				(type default)
			)
			(layer "B.Fab")
		)
		(fp_line
			(start 0.12065 0.3048)
			(end 0.67945 0.3048)
			(stroke
				(width 0.1)
				(type default)
			)
			(layer "B.Fab")
		)
		(fp_line
			(start 0.12065 0.2794)
			(end 0.12065 0.3048)
			(stroke
				(width 0.1)
				(type default)
			)
			(layer "B.Fab")
		)
		(fp_line
			(start 0.12065 -0.2794)
			(end -0.12065 -0.2794)
			(stroke
				(width 0.1)
				(type default)
			)
			(layer "B.Fab")
		)
		(fp_line
			(start 0.12065 -0.305054)
			(end 0.12065 -0.2794)
			(stroke
				(width 0.1)
				(type default)
			)
			(layer "B.Fab")
		)
		(fp_line
			(start -0.120396 0.3048)
			(end -0.120396 0.2794)
			(stroke
				(width 0.1)
				(type default)
			)
			(layer "B.Fab")
		)
		(fp_line
			(start -0.120396 0.2794)
			(end 0.12065 0.2794)
			(stroke
				(width 0.1)
				(type default)
			)
			(layer "B.Fab")
		)
		(fp_line
			(start -0.12065 -0.2794)
			(end -0.12065 -0.3048)
			(stroke
				(width 0.1)
				(type default)
			)
			(layer "B.Fab")
		)
		(fp_line
			(start -0.12065 -0.3048)
			(end -0.67945 -0.3048)
			(stroke
				(width 0.1)
				(type default)
			)
			(layer "B.Fab")
		)
		(fp_line
			(start -0.67945 0.3048)
			(end -0.120396 0.3048)
			(stroke
				(width 0.1)
				(type default)
			)
			(layer "B.Fab")
		)
		(fp_line
			(start -0.67945 -0.3048)
			(end -0.67945 0.3048)
			(stroke
				(width 0.1)
				(type default)
			)
			(layer "B.Fab")
		)
		(pad "1" smd circle
			(at 0.40005 0)
			(size 0 0)
			(layers "B.Cu" "B.Mask" "B.Paste")
			(net "PWR_LED_BUF_N")
		)
		(pad "2" smd circle
			(at -0.40005 0)
			(size 0 0)
			(layers "B.Cu" "B.Mask" "B.Paste")
			(net "PWR_LED_BUF_N_R")
		)
	)
)
